# BASEBOARD_FAB2 (Tioga Pass) — schematic netlist excerpt (pin names and nets, part order shuffled) for the footprints in the layout excerpt that follows; sources: Cadence DE-HDL packaged netlist, KiCad conversion of Wiwynn_Tioga_Pass_MB.brd

J4B1  SCONN288_H44441004  SCONN  pkg PIP  page 49
  \12v\(1)  = P12V_NVDIMM_DEF
  VSS(93)  = GND
  DQ(4)  = M_D_DQ<5>
  VSS(92)  = GND
  DQ(0)  = M_D_DQ<1>
  VSS(91)  = GND
  DQS9P  = M_D_DQS_DP<9>
  DQS9N  = M_D_DQS_DN<9>
  VSS(90)  = GND
  DQ(6)  = M_D_DQ<7>
  VSS(89)  = GND
  DQ(2)  = M_D_DQ<3>
  VSS(88)  = GND
  DQ(12)  = M_D_DQ<13>
  VSS(87)  = GND
  DQ(8)  = M_D_DQ<9>
  VSS(86)  = GND
  DQS10P  = M_D_DQS_DP<10>
  DQS10N  = M_D_DQS_DN<10>
  VSS(85)  = GND
  DQ(14)  = M_D_DQ<15>
  VSS(84)  = GND
  DQ(10)  = M_D_DQ<11>
  VSS(83)  = GND
  DQ(20)  = M_D_DQ<21>
  VSS(82)  = GND
  DQ(16)  = M_D_DQ<17>
  VSS(81)  = GND
  DQS11P  = M_D_DQS_DP<11>
  DQS11N  = M_D_DQS_DN<11>
  VSS(80)  = GND
  DQ(22)  = M_D_DQ<23>
  VSS(79)  = GND
  DQ(18)  = M_D_DQ<19>
  VSS(78)  = GND
  DQ(28)  = M_D_DQ<29>
  VSS(77)  = GND
  DQ(24)  = M_D_DQ<25>
  VSS(76)  = GND
  DQS12P  = M_D_DQS_DP<12>
  DQS12N  = M_D_DQS_DN<12>
  VSS(75)  = GND
  DQ(30)  = M_D_DQ<31>
  VSS(74)  = GND
  DQ(26)  = M_D_DQ<27>
  VSS(73)  = GND
  CB(4)  = M_D_ECC<5>
  VSS(72)  = GND
  CB(0)  = M_D_ECC<1>
  VSS(71)  = GND
  DQS17P  = M_D_DQS_DP<17>
  DQS17N  = M_D_DQS_DN<17>
  VSS(70)  = GND
  CB(6)  = M_D_ECC<7>
  VSS(69)  = GND
  CB(2)  = M_D_ECC<3>
  VSS(68)  = GND
  RESET_N  = M_DEF_RST_N
  VDD(25)  = PVDDQ_DEF
  CKE(0)  = M_D_CKE<0>
  VDD(24)  = PVDDQ_DEF
  ACT_N  = M_D_ACT_N
  BG(0)  = M_D_BG<0>
  VDD(23)  = PVDDQ_DEF
  A12  = M_D_MA<12>
  A9  = M_D_MA<9>
  VDD(22)  = PVDDQ_DEF
  A8  = M_D_MA<8>
  A6  = M_D_MA<6>
  VDD(21)  = PVDDQ_DEF
  A3  = M_D_MA<3>
  A1  = M_D_MA<1>
  VDD(20)  = PVDDQ_DEF
  CK0P  = M_D_CLK_DP<0>
  CK0N  = M_D_CLK_DN<0>
  VDD(19)  = PVDDQ_DEF
  VTT(1)  = PVTT_DEF
  EVENT_N  = FM_DIMM_EVENT_COD_N
  A0  = M_D_MA<0>
  VDD(18)  = PVDDQ_DEF
  BA(0)  = M_D_BA<0>
  A16_RAS_N  = M_D_MA<16>
  VDD(17)  = PVDDQ_DEF
  S0_N  = M_D_CS_N<0>
  VDD(16)  = PVDDQ_DEF
  A15_CAS_N  = M_D_MA<15>
  ODT(0)  = M_D_ODT<0>
  VDD(15)  = PVDDQ_DEF
  S1_N  = M_D_CS_N<1>
  VDD(14)  = PVDDQ_DEF
  ODT(1)  = M_D_ODT<1>
  VDD(13)  = PVDDQ_DEF
  S2_N_C(0)  = M_D_CS_N<2>
  VSS(67)  = GND
  DQ(36)  = M_D_DQ<37>
  VSS(66)  = GND
  DQ(32)  = M_D_DQ<33>
  VSS(65)  = GND
  DQS13P  = M_D_DQS_DP<13>
  DQS13N  = M_D_DQS_DN<13>
  VSS(64)  = GND
  DQ(38)  = M_D_DQ<39>
  VSS(63)  = GND
  DQ(34)  = M_D_DQ<35>
  VSS(62)  = GND
  DQ(44)  = M_D_DQ<45>
  VSS(61)  = GND
  DQ(40)  = M_D_DQ<41>
  VSS(60)  = GND
  DQS14P  = M_D_DQS_DP<14>
  DQS14N  = M_D_DQS_DN<14>
  VSS(59)  = GND
  DQ(46)  = M_D_DQ<47>
  VSS(58)  = GND
  DQ(42)  = M_D_DQ<43>
  VSS(57)  = GND
  DQ(52)  = M_D_DQ<53>
  VSS(56)  = GND
  DQ(48)  = M_D_DQ<49>
  VSS(55)  = GND
  DQS15P  = M_D_DQS_DP<15>
  DQS15N  = M_D_DQS_DN<15>
  VSS(54)  = GND
  DQ(54)  = M_D_DQ<55>
  VSS(53)  = GND
  DQ(50)  = M_D_DQ<51>
  VSS(52)  = GND
  DQ(60)  = M_D_DQ<61>
  VSS(51)  = GND
  DQ(56)  = M_D_DQ<57>
  VSS(50)  = GND
  DQS16P  = M_D_DQS_DP<16>
  DQS16N  = M_D_DQS_DN<16>
  VSS(49)  = GND
  DQ(62)  = M_D_DQ<63>
  VSS(48)  = GND
  DQ(58)  = M_D_DQ<59>
  VSS(47)  = GND
  SA(0)  = GND
  SA(1)  = GND
  SCL  = SMB_DDR_DEF_VPP_SCL
  VPP(4)  = PVPP_DEF
  VPP(3)  = PVPP_DEF
  RFU(2)  = TP_CH_D_DIMM_D0_RFU_2
  \12v\(0)  = P12V_NVDIMM_DEF
  VREFCA  = M_D_VREF
  VSS(46)  = GND
  DQ(5)  = M_D_DQ<4>
  VSS(45)  = GND
  DQ(1)  = M_D_DQ<0>
  VSS(44)  = GND
  DQS0N  = M_D_DQS_DN<0>
  DQS0P  = M_D_DQS_DP<0>
  VSS(43)  = GND
  DQ(7)  = M_D_DQ<6>
  VSS(42)  = GND
  DQ(3)  = M_D_DQ<2>
  VSS(41)  = GND
  DQ(13)  = M_D_DQ<12>
  VSS(40)  = GND
  DQ(9)  = M_D_DQ<8>
  VSS(39)  = GND
  DQS1N  = M_D_DQS_DN<1>
  DQS1P  = M_D_DQS_DP<1>
  VSS(38)  = GND
  DQ(15)  = M_D_DQ<14>
  VSS(37)  = GND
  DQ(11)  = M_D_DQ<10>
  VSS(36)  = GND
  DQ(21)  = M_D_DQ<20>
  VSS(35)  = GND
  DQ(17)  = M_D_DQ<16>
  VSS(34)  = GND
  DQS2N  = M_D_DQS_DN<2>
  DQS2P  = M_D_DQS_DP<2>
  VSS(33)  = GND
  DQ(23)  = M_D_DQ<22>
  VSS(32)  = GND
  DQ(19)  = M_D_DQ<18>
  VSS(31)  = GND
  DQ(29)  = M_D_DQ<28>
  VSS(30)  = GND
  DQ(25)  = M_D_DQ<24>
  VSS(29)  = GND
  DQS3N  = M_D_DQS_DN<3>
  DQS3P  = M_D_DQS_DP<3>
  VSS(28)  = GND
  DQ(31)  = M_D_DQ<30>
  VSS(27)  = GND
  DQ(27)  = M_D_DQ<26>
  VSS(26)  = GND
  CB(5)  = M_D_ECC<4>
  VSS(25)  = GND
  CB(1)  = M_D_ECC<0>
  VSS(24)  = GND
  DQS8N  = M_D_DQS_DN<8>
  DQS8P  = M_D_DQS_DP<8>
  VSS(23)  = GND
  CB(7)  = M_D_ECC<6>
  VSS(22)  = GND
  CB(3)  = M_D_ECC<2>
  VSS(21)  = GND
  CKE(1)  = M_D_CKE<1>
  VDD(12)  = PVDDQ_DEF
  RFU(0)  = TP_CH_D_DIMM_D0_RFU_0
  VDD(11)  = PVDDQ_DEF
  BG(1)  = M_D_BG<1>
  ALERT_N  = M_D_ALERT_N
  VDD(10)  = PVDDQ_DEF
  A11  = M_D_MA<11>
  A7  = M_D_MA<7>
  VDD(9)  = PVDDQ_DEF
  A5  = M_D_MA<5>
  A4  = M_D_MA<4>
  VDD(8)  = PVDDQ_DEF
  A2  = M_D_MA<2>
  VDD(7)  = PVDDQ_DEF
  CK1P  = M_D_CLK_DP<1>
  CK1N  = M_D_CLK_DN<1>
  VDD(6)  = PVDDQ_DEF
  VTT(0)  = PVTT_DEF
  PAR  = M_D_PAR
  VDD(5)  = PVDDQ_DEF
  BA(1)  = M_D_BA<1>
  A10  = M_D_MA<10>
  VDD(4)  = PVDDQ_DEF
  RFU(1)  = TP_CH_D_DIMM_D0_RFU_1
  A14_WE_N  = M_D_MA<14>
  VDD(3)  = PVDDQ_DEF
  SAVE_N_NC  = FM_ADR_COMPLETE_DEF_N
  VDD(2)  = PVDDQ_DEF
  A13  = M_D_MA<13>
  VDD(1)  = PVDDQ_DEF
  A17  = M_D_MA<17>
  C(2)  = M_D_C<2>
  VDD(0)  = PVDDQ_DEF
  S3_N_C(1)  = M_D_CS_N<3>
  SA(2)  = GND
  VSS(20)  = GND
  DQ(37)  = M_D_DQ<36>
  VSS(19)  = GND
  DQ(33)  = M_D_DQ<32>
  VSS(18)  = GND
  DQS4N  = M_D_DQS_DN<4>
  DQS4P  = M_D_DQS_DP<4>
  VSS(17)  = GND
  DQ(39)  = M_D_DQ<38>
  VSS(16)  = GND
  DQ(35)  = M_D_DQ<34>
  VSS(15)  = GND
  DQ(45)  = M_D_DQ<44>
  VSS(14)  = GND
  DQ(41)  = M_D_DQ<40>
  VSS(13)  = GND
  DQS5N  = M_D_DQS_DN<5>
  DQS5P  = M_D_DQS_DP<5>
  VSS(12)  = GND
  DQ(47)  = M_D_DQ<46>
  VSS(11)  = GND
  DQ(43)  = M_D_DQ<42>
  VSS(10)  = GND
  DQ(53)  = M_D_DQ<52>
  VSS(9)  = GND
  DQ(49)  = M_D_DQ<48>
  VSS(8)  = GND
  DQS6N  = M_D_DQS_DN<6>
  DQS6P  = M_D_DQS_DP<6>
  VSS(7)  = GND
  DQ(55)  = M_D_DQ<54>
  VSS(6)  = GND
  DQ(51)  = M_D_DQ<50>
  VSS(5)  = GND
  DQ(61)  = M_D_DQ<60>
  VSS(4)  = GND
  DQ(57)  = M_D_DQ<56>
  VSS(3)  = GND
  DQS7N  = M_D_DQS_DN<7>
  DQS7P  = M_D_DQS_DP<7>
  VSS(2)  = GND
  DQ(63)  = M_D_DQ<62>
  VSS(1)  = GND
  DQ(59)  = M_D_DQ<58>
  VSS(0)  = GND
  VDDSPD  = PVPP_DEF
  SDA  = SMB_DDR_DEF_VPP_SDA
  VPP(1)  = PVPP_DEF
  VPP(0)  = PVPP_DEF
  VPP(2)  = PVPP_DEF

(kicad_pcb
	(version 20260206)
	(generator "pcbnew")
	(generator_version "10.0")
	(general
		(thickness 1.6)
		(legacy_teardrops no)
	)
	(paper "A4")
	(title_block
		(title "Wiwynn_Tioga_Pass_MB.brd")
		(comment 1 "Tioga Pass / footprint 990 of 4770 (J4B1), pads 1-51 of 291")
	)
	(layers
		(0 "F.Cu" signal "TOP")
		(4 "In1.Cu" signal "L2GND")
		(6 "In2.Cu" signal "L3")
		(8 "In3.Cu" signal "L4GND")
		(10 "In4.Cu" signal "L5")
		(12 "In5.Cu" signal "L6GND")
		(14 "In6.Cu" signal "L7VCC")
		(16 "In7.Cu" signal "L8VCC")
		(18 "In8.Cu" signal "L9GND")
		(20 "In9.Cu" signal "L10")
		(22 "In10.Cu" signal "L11GND")
		(24 "In11.Cu" signal "L12")
		(26 "In12.Cu" signal "L13GND")
		(2 "B.Cu" signal "BOTTOM")
		(9 "F.Adhes" user "F.Adhesive")
		(11 "B.Adhes" user "B.Adhesive")
		(13 "F.Paste" user "Package Geometry/Pastemask Top")
		(15 "B.Paste" user "Package Geometry/Pastemask Bottom")
		(5 "F.SilkS" user "Ref Des/Silkscreen Top")
		(7 "B.SilkS" user "Ref Des/Silkscreen Bottom")
		(1 "F.Mask" user "Board Geometry/Soldermask Top")
		(3 "B.Mask" user "Board Geometry/Soldermask Bottom")
		(17 "Dwgs.User" user "User.Drawings")
		(19 "Cmts.User" user "User.Comments")
		(21 "Eco1.User" user "User.Eco1")
		(23 "Eco2.User" user "User.Eco2")
		(25 "Edge.Cuts" user "Board Geometry/Outline")
		(27 "Margin" user)
		(31 "F.CrtYd" user "Package Geometry/Place Bound Top")
		(29 "B.CrtYd" user "Package Geometry/Place Bound Bottom")
		(35 "F.Fab" user "Ref Des/Assembly Top")
		(33 "B.Fab" user "Ref Des/Assembly Bottom")
	)
	(footprint ""
		(layer "F.Cu")
		(at 194.700398 -133.0706 90)
		(property "Reference" "J4B1"
			(at -5.087112 42.28211 0)
			(unlocked yes)
			(layer "F.SilkS")
			(effects
				(font
					(size 0.7874 0.5842)
					(thickness 0.1524)
				)
				(justify left)
			)
		)
		(property "Value" ""
			(at 0 0 90)
			(layer "F.Fab")
			(effects
				(font
					(size 1.27 1.27)
				)
			)
		)
		(duplicate_pad_numbers_are_jumpers no)
		(pad "" thru_hole circle
			(at 2.29997 -5.649976 90)
			(size 2.8194 2.8194)
			(drill 2.4384)
			(layers "*.Cu" "*.Mask")
			(remove_unused_layers no)
			(clearance 0.127)
			(thermal_gap 0.127)
		)
		(pad "" thru_hole oval
			(at 2.29997 68.90004 90)
			(size 2.8194 1.5748)
			(drill oval 2.4384 1.1938)
			(layers "*.Cu" "*.Mask")
			(remove_unused_layers no)
			(clearance 0.127)
			(thermal_gap 0.127)
		)
		(pad "" thru_hole circle
			(at 2.29997 132.299964 90)
			(size 2.8194 2.8194)
			(drill 2.4384)
			(layers "*.Cu" "*.Mask")
			(remove_unused_layers no)
			(clearance 0.127)
			(thermal_gap 0.127)
		)
		(pad "1" smd rect
			(at 0 0 90)
			(size 1.8034 0.508)
			(layers "F.Cu" "F.Mask" "F.Paste")
			(net "P12V_NVDIMM_DEF")
		)
		(pad "2" smd rect
			(at 0 0.849884 90)
			(size 1.8034 0.508)
			(layers "F.Cu" "F.Mask" "F.Paste")
			(net "GND")
		)
		(pad "3" smd rect
			(at 0 1.700022 90)
			(size 1.8034 0.508)
			(layers "F.Cu" "F.Mask" "F.Paste")
			(net "M_D_DQ<5>")
		)
		(pad "4" smd rect
			(at 0 2.549906 90)
			(size 1.8034 0.508)
			(layers "F.Cu" "F.Mask" "F.Paste")
			(net "GND")
		)
		(pad "5" smd rect
			(at 0 3.400044 90)
			(size 1.8034 0.508)
			(layers "F.Cu" "F.Mask" "F.Paste")
			(net "M_D_DQ<1>")
		)
		(pad "6" smd rect
			(at 0 4.249928 90)
			(size 1.8034 0.508)
			(layers "F.Cu" "F.Mask" "F.Paste")
			(net "GND")
		)
		(pad "7" smd rect
			(at 0 5.100066 90)
			(size 1.8034 0.508)
			(layers "F.Cu" "F.Mask" "F.Paste")
			(net "M_D_DQS_DP<9>")
		)
		(pad "8" smd rect
			(at 0 5.94995 90)
			(size 1.8034 0.508)
			(layers "F.Cu" "F.Mask" "F.Paste")
			(net "M_D_DQS_DN<9>")
		)
		(pad "9" smd rect
			(at 0 6.800088 90)
			(size 1.8034 0.508)
			(layers "F.Cu" "F.Mask" "F.Paste")
			(net "GND")
		)
		(pad "10" smd rect
			(at 0 7.649972 90)
			(size 1.8034 0.508)
			(layers "F.Cu" "F.Mask" "F.Paste")
			(net "M_D_DQ<7>")
		)
		(pad "11" smd rect
			(at 0 8.50011 90)
			(size 1.8034 0.508)
			(layers "F.Cu" "F.Mask" "F.Paste")
			(net "GND")
		)
		(pad "12" smd rect
			(at 0 9.349994 90)
			(size 1.8034 0.508)
			(layers "F.Cu" "F.Mask" "F.Paste")
			(net "M_D_DQ<3>")
		)
		(pad "13" smd rect
			(at 0 10.199878 90)
			(size 1.8034 0.508)
			(layers "F.Cu" "F.Mask" "F.Paste")
			(net "GND")
		)
		(pad "14" smd rect
			(at 0 11.050016 90)
			(size 1.8034 0.508)
			(layers "F.Cu" "F.Mask" "F.Paste")
			(net "M_D_DQ<13>")
		)
		(pad "15" smd rect
			(at 0 11.8999 90)
			(size 1.8034 0.508)
			(layers "F.Cu" "F.Mask" "F.Paste")
			(net "GND")
		)
		(pad "16" smd rect
			(at 0 12.750038 90)
			(size 1.8034 0.508)
			(layers "F.Cu" "F.Mask" "F.Paste")
			(net "M_D_DQ<9>")
		)
		(pad "17" smd rect
			(at 0 13.599922 90)
			(size 1.8034 0.508)
			(layers "F.Cu" "F.Mask" "F.Paste")
			(net "GND")
		)
		(pad "18" smd rect
			(at 0 14.45006 90)
			(size 1.8034 0.508)
			(layers "F.Cu" "F.Mask" "F.Paste")
			(net "M_D_DQS_DP<10>")
		)
		(pad "19" smd rect
			(at 0 15.299944 90)
			(size 1.8034 0.508)
			(layers "F.Cu" "F.Mask" "F.Paste")
			(net "M_D_DQS_DN<10>")
		)
		(pad "20" smd rect
			(at 0 16.150082 90)
			(size 1.8034 0.508)
			(layers "F.Cu" "F.Mask" "F.Paste")
			(net "GND")
		)
		(pad "21" smd rect
			(at 0 16.999966 90)
			(size 1.8034 0.508)
			(layers "F.Cu" "F.Mask" "F.Paste")
			(net "M_D_DQ<15>")
		)
		(pad "22" smd rect
			(at 0 17.850104 90)
			(size 1.8034 0.508)
			(layers "F.Cu" "F.Mask" "F.Paste")
			(net "GND")
		)
		(pad "23" smd rect
			(at 0 18.699988 90)
			(size 1.8034 0.508)
			(layers "F.Cu" "F.Mask" "F.Paste")
			(net "M_D_DQ<11>")
		)
		(pad "24" smd rect
			(at 0 19.550126 90)
			(size 1.8034 0.508)
			(layers "F.Cu" "F.Mask" "F.Paste")
			(net "GND")
		)
		(pad "25" smd rect
			(at 0 20.40001 90)
			(size 1.8034 0.508)
			(layers "F.Cu" "F.Mask" "F.Paste")
			(net "M_D_DQ<21>")
		)
		(pad "26" smd rect
			(at 0 21.249894 90)
			(size 1.8034 0.508)
			(layers "F.Cu" "F.Mask" "F.Paste")
			(net "GND")
		)
		(pad "27" smd rect
			(at 0 22.100032 90)
			(size 1.8034 0.508)
			(layers "F.Cu" "F.Mask" "F.Paste")
			(net "M_D_DQ<17>")
		)
		(pad "28" smd rect
			(at 0 22.949916 90)
			(size 1.8034 0.508)
			(layers "F.Cu" "F.Mask" "F.Paste")
			(net "GND")
		)
		(pad "29" smd rect
			(at 0 23.800054 90)
			(size 1.8034 0.508)
			(layers "F.Cu" "F.Mask" "F.Paste")
			(net "M_D_DQS_DP<11>")
		)
		(pad "30" smd rect
			(at 0 24.649938 90)
			(size 1.8034 0.508)
			(layers "F.Cu" "F.Mask" "F.Paste")
			(net "M_D_DQS_DN<11>")
		)
		(pad "31" smd rect
			(at 0 25.500076 90)
			(size 1.8034 0.508)
			(layers "F.Cu" "F.Mask" "F.Paste")
			(net "GND")
		)
		(pad "32" smd rect
			(at 0 26.34996 90)
			(size 1.8034 0.508)
			(layers "F.Cu" "F.Mask" "F.Paste")
			(net "M_D_DQ<23>")
		)
		(pad "33" smd rect
			(at 0 27.200098 90)
			(size 1.8034 0.508)
			(layers "F.Cu" "F.Mask" "F.Paste")
			(net "GND")
		)
		(pad "34" smd rect
			(at 0 28.049982 90)
			(size 1.8034 0.508)
			(layers "F.Cu" "F.Mask" "F.Paste")
			(net "M_D_DQ<19>")
		)
		(pad "35" smd rect
			(at 0 28.90012 90)
			(size 1.8034 0.508)
			(layers "F.Cu" "F.Mask" "F.Paste")
			(net "GND")
		)
		(pad "36" smd rect
			(at 0 29.750004 90)
			(size 1.8034 0.508)
			(layers "F.Cu" "F.Mask" "F.Paste")
			(net "M_D_DQ<29>")
		)
		(pad "37" smd rect
			(at 0 30.599888 90)
			(size 1.8034 0.508)
			(layers "F.Cu" "F.Mask" "F.Paste")
			(net "GND")
		)
		(pad "38" smd rect
			(at 0 31.450026 90)
			(size 1.8034 0.508)
			(layers "F.Cu" "F.Mask" "F.Paste")
			(net "M_D_DQ<25>")
		)
		(pad "39" smd rect
			(at 0 32.29991 90)
			(size 1.8034 0.508)
			(layers "F.Cu" "F.Mask" "F.Paste")
			(net "GND")
		)
		(pad "40" smd rect
			(at 0 33.150048 90)
			(size 1.8034 0.508)
			(layers "F.Cu" "F.Mask" "F.Paste")
			(net "M_D_DQS_DP<12>")
		)
		(pad "41" smd rect
			(at 0 33.999932 90)
			(size 1.8034 0.508)
			(layers "F.Cu" "F.Mask" "F.Paste")
			(net "M_D_DQS_DN<12>")
		)
		(pad "42" smd rect
			(at 0 34.85007 90)
			(size 1.8034 0.508)
			(layers "F.Cu" "F.Mask" "F.Paste")
			(net "GND")
		)
		(pad "43" smd rect
			(at 0 35.699954 90)
			(size 1.8034 0.508)
			(layers "F.Cu" "F.Mask" "F.Paste")
			(net "M_D_DQ<31>")
		)
		(pad "44" smd rect
			(at 0 36.550092 90)
			(size 1.8034 0.508)
			(layers "F.Cu" "F.Mask" "F.Paste")
			(net "GND")
		)
		(pad "45" smd rect
			(at 0 37.399976 90)
			(size 1.8034 0.508)
			(layers "F.Cu" "F.Mask" "F.Paste")
			(net "M_D_DQ<27>")
		)
		(pad "46" smd rect
			(at 0 38.250114 90)
			(size 1.8034 0.508)
			(layers "F.Cu" "F.Mask" "F.Paste")
			(net "GND")
		)
		(pad "47" smd rect
			(at 0 39.099998 90)
			(size 1.8034 0.508)
			(layers "F.Cu" "F.Mask" "F.Paste")
			(net "M_D_ECC<5>")
		)
		(pad "48" smd rect
			(at 0 39.949882 90)
			(size 1.8034 0.508)
			(layers "F.Cu" "F.Mask" "F.Paste")
			(net "GND")
		)
	)
)
